# BASEBOARD_FAB2 (Tioga Pass) — schematic netlist excerpt (pin names and nets, part order shuffled) for the footprints in the layout excerpt that follows; sources: Cadence DE-HDL packaged netlist, KiCad conversion of Wiwynn_Tioga_Pass_MB.brd

C2T30  CAP_A  0.1UF 16V 10% X7R  pkg 0402V  page 101 : A = P3V3_STBY_MNG ; B = GND
C2L49  CAP_A  0.01UF 25V 10% X7R  pkg 0402V  page 172 : A = SATA6G_S1_RX_C_DP ; B = SATA6G_S1_RX_DP

(kicad_pcb
	(version 20260206)
	(generator "pcbnew")
	(generator_version "10.0")
	(general
		(thickness 1.6)
		(legacy_teardrops no)
	)
	(paper "A4")
	(title_block
		(title "Wiwynn_Tioga_Pass_MB.brd")
		(comment 1 "Tioga Pass / footprints 4100-4101 of 4770")
	)
	(layers
		(0 "F.Cu" signal "TOP")
		(4 "In1.Cu" signal "L2GND")
		(6 "In2.Cu" signal "L3")
		(8 "In3.Cu" signal "L4GND")
		(10 "In4.Cu" signal "L5")
		(12 "In5.Cu" signal "L6GND")
		(14 "In6.Cu" signal "L7VCC")
		(16 "In7.Cu" signal "L8VCC")
		(18 "In8.Cu" signal "L9GND")
		(20 "In9.Cu" signal "L10")
		(22 "In10.Cu" signal "L11GND")
		(24 "In11.Cu" signal "L12")
		(26 "In12.Cu" signal "L13GND")
		(2 "B.Cu" signal "BOTTOM")
		(9 "F.Adhes" user "F.Adhesive")
		(11 "B.Adhes" user "B.Adhesive")
		(13 "F.Paste" user "Package Geometry/Pastemask Top")
		(15 "B.Paste" user "Package Geometry/Pastemask Bottom")
		(5 "F.SilkS" user "Ref Des/Silkscreen Top")
		(7 "B.SilkS" user "Ref Des/Silkscreen Bottom")
		(1 "F.Mask" user "Board Geometry/Soldermask Top")
		(3 "B.Mask" user "Board Geometry/Soldermask Bottom")
		(17 "Dwgs.User" user "User.Drawings")
		(19 "Cmts.User" user "User.Comments")
		(21 "Eco1.User" user "User.Eco1")
		(23 "Eco2.User" user "User.Eco2")
		(25 "Edge.Cuts" user "Board Geometry/Outline")
		(27 "Margin" user)
		(31 "F.CrtYd" user "Package Geometry/Place Bound Top")
		(29 "B.CrtYd" user "Package Geometry/Place Bound Bottom")
		(35 "F.Fab" user "Ref Des/Assembly Top")
		(33 "B.Fab" user "Ref Des/Assembly Bottom")
	)
	(footprint ""
		(layer "B.Cu")
		(at 481.2665 -30.226 -90)
		(property "Reference" "C2T30"
			(at 0 0 90)
			(layer "B.SilkS")
			(hide yes)
			(effects
				(font
					(size 1.27 1.27)
				)
				(justify mirror)
			)
		)
		(property "Value" ""
			(at 0 0 90)
			(layer "B.Fab")
			(effects
				(font
					(size 1.27 1.27)
				)
				(justify mirror)
			)
		)
		(duplicate_pad_numbers_are_jumpers no)
		(fp_poly
			(pts
				(xy -0.3048 -0.1016) (xy -0.3048 0.9906) (xy 0.3048 0.9906) (xy 0.3048 -0.1016)
			)
			(stroke
				(width 0)
				(type default)
			)
			(fill no)
			(layer "B.CrtYd")
		)
		(fp_line
			(start -0.3048 0.9906)
			(end -0.3048 -0.1016)
			(stroke
				(width 0.1)
				(type default)
			)
			(layer "B.Fab")
		)
		(fp_line
			(start 0.3048 0.9906)
			(end -0.3048 0.9906)
			(stroke
				(width 0.1)
				(type default)
			)
			(layer "B.Fab")
		)
		(fp_line
			(start -0.3048 -0.1016)
			(end 0.3048 -0.1016)
			(stroke
				(width 0.1)
				(type default)
			)
			(layer "B.Fab")
		)
		(fp_line
			(start 0.3048 -0.1016)
			(end 0.3048 0.9906)
			(stroke
				(width 0.1)
				(type default)
			)
			(layer "B.Fab")
		)
		(pad "1" smd rect
			(at 0 0 90)
			(size 0.508 0.508)
			(layers "B.Cu" "B.Mask" "B.Paste")
			(net "P3V3_STBY_MNG")
		)
		(pad "2" smd rect
			(at 0 0.889 90)
			(size 0.508 0.508)
			(layers "B.Cu" "B.Mask" "B.Paste")
			(net "GND")
		)
		(zone
			(layer "B.Cu")
			(hatch none 0.5)
			(connect_pads
				(clearance 0)
			)
			(min_thickness 0.25)
			(keepout
				(tracks not_allowed)
				(vias allowed)
				(pads allowed)
				(copperpour not_allowed)
				(footprints allowed)
			)
			(placement
				(enabled no)
				(sheetname "")
			)
			(fill
				(thermal_gap 0.5)
				(thermal_bridge_width 0.5)
				(island_removal_mode 0)
			)
			(polygon
				(pts
					(xy 480.6315 -29.972) (xy 480.6315 -30.48) (xy 481.0125 -30.48) (xy 481.0125 -29.972)
				)
			)
		)
		(zone
			(layer "B.Cu")
			(hatch none 0.5)
			(connect_pads
				(clearance 0)
			)
			(min_thickness 0.25)
			(keepout
				(tracks allowed)
				(vias not_allowed)
				(pads allowed)
				(copperpour not_allowed)
				(footprints allowed)
			)
			(placement
				(enabled no)
				(sheetname "")
			)
			(fill
				(thermal_gap 0.5)
				(thermal_bridge_width 0.5)
				(island_removal_mode 0)
			)
			(polygon
				(pts
					(xy 481.0125 -29.972) (xy 481.0125 -30.48) (xy 480.6315 -30.48) (xy 480.6315 -29.972)
				)
			)
		)
	)
	(footprint ""
		(layer "B.Cu")
		(at 435.381654 -141.002512 180)
		(property "Reference" "C2L49"
			(at 0 0 0)
			(layer "B.SilkS")
			(hide yes)
			(effects
				(font
					(size 1.27 1.27)
				)
				(justify mirror)
			)
		)
		(property "Value" ""
			(at 0 0 0)
			(layer "B.Fab")
			(effects
				(font
					(size 1.27 1.27)
				)
				(justify mirror)
			)
		)
		(duplicate_pad_numbers_are_jumpers no)
		(fp_poly
			(pts
				(xy -0.3048 -0.1016) (xy -0.3048 0.9906) (xy 0.3048 0.9906) (xy 0.3048 -0.1016)
			)
			(stroke
				(width 0)
				(type default)
			)
			(fill no)
			(layer "B.CrtYd")
		)
		(fp_line
			(start 0.3048 0.9906)
			(end -0.3048 0.9906)
			(stroke
				(width 0.1)
				(type default)
			)
			(layer "B.Fab")
		)
		(fp_line
			(start 0.3048 -0.1016)
			(end 0.3048 0.9906)
			(stroke
				(width 0.1)
				(type default)
			)
			(layer "B.Fab")
		)
		(fp_line
			(start -0.3048 0.9906)
			(end -0.3048 -0.1016)
			(stroke
				(width 0.1)
				(type default)
			)
			(layer "B.Fab")
		)
		(fp_line
			(start -0.3048 -0.1016)
			(end 0.3048 -0.1016)
			(stroke
				(width 0.1)
				(type default)
			)
			(layer "B.Fab")
		)
		(pad "1" smd rect
			(at 0 0)
			(size 0.508 0.508)
			(layers "B.Cu" "B.Mask" "B.Paste")
			(net "SATA6G_S1_RX_C_DP")
		)
		(pad "2" smd rect
			(at 0 0.889)
			(size 0.508 0.508)
			(layers "B.Cu" "B.Mask" "B.Paste")
			(net "SATA6G_S1_RX_DP")
		)
		(zone
			(layer "B.Cu")
			(hatch none 0.5)
			(connect_pads
				(clearance 0)
			)
			(min_thickness 0.25)
			(keepout
				(tracks not_allowed)
				(vias allowed)
				(pads allowed)
				(copperpour not_allowed)
				(footprints allowed)
			)
			(placement
				(enabled no)
				(sheetname "")
			)
			(fill
				(thermal_gap 0.5)
				(thermal_bridge_width 0.5)
				(island_removal_mode 0)
			)
			(polygon
				(pts
					(xy 435.127654 -141.637512) (xy 435.635654 -141.637512) (xy 435.635654 -141.256512) (xy 435.127654 -141.256512)
				)
			)
		)
		(zone
			(layer "B.Cu")
			(hatch none 0.5)
			(connect_pads
				(clearance 0)
			)
			(min_thickness 0.25)
			(keepout
				(tracks allowed)
				(vias not_allowed)
				(pads allowed)
				(copperpour not_allowed)
				(footprints allowed)
			)
			(placement
				(enabled no)
				(sheetname "")
			)
			(fill
				(thermal_gap 0.5)
				(thermal_bridge_width 0.5)
				(island_removal_mode 0)
			)
			(polygon
				(pts
					(xy 435.127654 -141.256512) (xy 435.635654 -141.256512) (xy 435.635654 -141.637512) (xy 435.127654 -141.637512)
				)
			)
		)
	)
)
